(kicad_pcb
	(version 20260206)
	(generator "pcbnew")
	(generator_version "10.0")
	(general
		(thickness 1.6)
		(legacy_teardrops no)
	)
	(paper "A4")
	(title_block
		(title "01162023_DA0F0TEBIF0_F0T_Expander_BD_F_brd_V02_OCP.brd")
		(comment 1 "Grand Teton / footprints 2201-2207 of 9728")
	)
	(layers
		(0 "F.Cu" signal "TOP")
		(4 "In1.Cu" signal "GND")
		(6 "In2.Cu" signal "VCC")
		(8 "In3.Cu" signal "VCC1")
		(10 "In4.Cu" signal "GND1")
		(12 "In5.Cu" signal "IN1")
		(14 "In6.Cu" signal "GND2")
		(16 "In7.Cu" signal "IN2")
		(18 "In8.Cu" signal "GND3")
		(20 "In9.Cu" signal "IN3")
		(22 "In10.Cu" signal "GND4")
		(24 "In11.Cu" signal "IN4")
		(26 "In12.Cu" signal "GND5")
		(28 "In13.Cu" signal "IN5")
		(30 "In14.Cu" signal "GND6")
		(32 "In15.Cu" signal "IN6")
		(34 "In16.Cu" signal "GND7")
		(2 "B.Cu" signal "BOTTOM")
		(9 "F.Adhes" user "F.Adhesive")
		(11 "B.Adhes" user "B.Adhesive")
		(13 "F.Paste" user "Package Geometry/Pastemask Top")
		(15 "B.Paste" user "Package Geometry/Pastemask Bottom")
		(5 "F.SilkS" user "Ref Des/Silkscreen Top")
		(7 "B.SilkS" user "Ref Des/Silkscreen Bottom")
		(1 "F.Mask" user "Board Geometry/Soldermask Top")
		(3 "B.Mask" user "Board Geometry/Soldermask Bottom")
		(17 "Dwgs.User" user "User.Drawings")
		(19 "Cmts.User" user "User.Comments")
		(21 "Eco1.User" user "User.Eco1")
		(23 "Eco2.User" user "User.Eco2")
		(25 "Edge.Cuts" user "Board Geometry/Outline")
		(27 "Margin" user)
		(31 "F.CrtYd" user "Package Geometry/Place Bound Top")
		(29 "B.CrtYd" user "Package Geometry/Place Bound Bottom")
		(35 "F.Fab" user "Ref Des/Assembly Top")
		(33 "B.Fab" user "Ref Des/Assembly Bottom")
	)
	(footprint ""
		(layer "F.Cu")
		(at 268.838426 -112.809782)
		(property "Reference" "C472"
			(at 0 0 0)
			(layer "F.SilkS")
			(hide yes)
			(effects
				(font
					(size 1.27 1.27)
				)
			)
		)
		(property "Value" ""
			(at 0 0 0)
			(layer "F.Fab")
			(effects
				(font
					(size 1.27 1.27)
				)
			)
		)
		(duplicate_pad_numbers_are_jumpers no)
		(fp_line
			(start -0.299974 -0.150114)
			(end 0.299974 -0.150114)
			(stroke
				(width 0.1)
				(type default)
			)
			(layer "F.Fab")
		)
		(fp_line
			(start -0.299974 0.150114)
			(end -0.299974 -0.150114)
			(stroke
				(width 0.1)
				(type default)
			)
			(layer "F.Fab")
		)
		(fp_line
			(start 0.299974 -0.150114)
			(end 0.299974 0.150114)
			(stroke
				(width 0.1)
				(type default)
			)
			(layer "F.Fab")
		)
		(fp_line
			(start 0.299974 0.150114)
			(end -0.299974 0.150114)
			(stroke
				(width 0.1)
				(type default)
			)
			(layer "F.Fab")
		)
		(pad "1" smd rect
			(at -0.2667 0)
			(size 0.3048 0.381)
			(layers "F.Cu" "F.Mask" "F.Paste")
			(net "P5E_PEX2_STN1_TX_DP<23>")
		)
		(pad "2" smd rect
			(at 0.2667 0)
			(size 0.3048 0.381)
			(layers "F.Cu" "F.Mask" "F.Paste")
			(net "P5E_PEX2_STN1_TX_C_DP<23>")
		)
	)
	(footprint ""
		(layer "F.Cu")
		(at 7.613396 -135.058404 180)
		(property "Reference" "C2853"
			(at 0 0 180)
			(layer "F.SilkS")
			(hide yes)
			(effects
				(font
					(size 1.27 1.27)
				)
			)
		)
		(property "Value" ""
			(at 0 0 180)
			(layer "F.Fab")
			(effects
				(font
					(size 1.27 1.27)
				)
			)
		)
		(duplicate_pad_numbers_are_jumpers no)
		(fp_line
			(start 0.7874 0.4064)
			(end -0.7874 0.4064)
			(stroke
				(width 0.1524)
				(type default)
			)
			(layer "F.SilkS")
		)
		(fp_line
			(start 0.7874 -0.4064)
			(end 0.7874 0.4064)
			(stroke
				(width 0.1524)
				(type default)
			)
			(layer "F.SilkS")
		)
		(fp_line
			(start -0.7874 0.4064)
			(end -0.7874 -0.4064)
			(stroke
				(width 0.1524)
				(type default)
			)
			(layer "F.SilkS")
		)
		(fp_line
			(start -0.7874 -0.4064)
			(end 0.7874 -0.4064)
			(stroke
				(width 0.1524)
				(type default)
			)
			(layer "F.SilkS")
		)
		(fp_line
			(start 0.67945 0.3048)
			(end 0.120396 0.3048)
			(stroke
				(width 0.1)
				(type default)
			)
			(layer "F.Fab")
		)
		(fp_line
			(start 0.67945 -0.3048)
			(end 0.67945 0.3048)
			(stroke
				(width 0.1)
				(type default)
			)
			(layer "F.Fab")
		)
		(fp_line
			(start 0.12065 -0.2794)
			(end 0.12065 -0.3048)
			(stroke
				(width 0.1)
				(type default)
			)
			(layer "F.Fab")
		)
		(fp_line
			(start 0.12065 -0.3048)
			(end 0.67945 -0.3048)
			(stroke
				(width 0.1)
				(type default)
			)
			(layer "F.Fab")
		)
		(fp_line
			(start 0.120396 0.3048)
			(end 0.120396 0.2794)
			(stroke
				(width 0.1)
				(type default)
			)
			(layer "F.Fab")
		)
		(fp_line
			(start 0.120396 0.2794)
			(end -0.12065 0.2794)
			(stroke
				(width 0.1)
				(type default)
			)
			(layer "F.Fab")
		)
		(fp_line
			(start -0.12065 0.3048)
			(end -0.67945 0.3048)
			(stroke
				(width 0.1)
				(type default)
			)
			(layer "F.Fab")
		)
		(fp_line
			(start -0.12065 0.2794)
			(end -0.12065 0.3048)
			(stroke
				(width 0.1)
				(type default)
			)
			(layer "F.Fab")
		)
		(fp_line
			(start -0.12065 -0.2794)
			(end 0.12065 -0.2794)
			(stroke
				(width 0.1)
				(type default)
			)
			(layer "F.Fab")
		)
		(fp_line
			(start -0.12065 -0.305054)
			(end -0.12065 -0.2794)
			(stroke
				(width 0.1)
				(type default)
			)
			(layer "F.Fab")
		)
		(fp_line
			(start -0.67945 0.3048)
			(end -0.67945 -0.305054)
			(stroke
				(width 0.1)
				(type default)
			)
			(layer "F.Fab")
		)
		(fp_line
			(start -0.67945 -0.305054)
			(end -0.12065 -0.305054)
			(stroke
				(width 0.1)
				(type default)
			)
			(layer "F.Fab")
		)
		(pad "1" smd circle
			(at -0.40005 0 180)
			(size 0 0)
			(layers "F.Cu" "F.Mask" "F.Paste")
			(net "P12V_NIC0_EN_R")
		)
		(pad "2" smd circle
			(at 0.40005 0 180)
			(size 0 0)
			(layers "F.Cu" "F.Mask" "F.Paste")
			(net "GND")
		)
	)
	(footprint ""
		(layer "F.Cu")
		(at 364.731808 -162.003994 -90)
		(property "Reference" "R958"
			(at 0 0 270)
			(layer "F.SilkS")
			(hide yes)
			(effects
				(font
					(size 1.27 1.27)
				)
			)
		)
		(property "Value" ""
			(at 0 0 270)
			(layer "F.Fab")
			(effects
				(font
					(size 1.27 1.27)
				)
			)
		)
		(duplicate_pad_numbers_are_jumpers no)
		(fp_line
			(start -0.7874 0.4064)
			(end -0.7874 -0.4064)
			(stroke
				(width 0.1524)
				(type default)
			)
			(layer "F.SilkS")
		)
		(fp_line
			(start 0.7874 0.4064)
			(end -0.7874 0.4064)
			(stroke
				(width 0.1524)
				(type default)
			)
			(layer "F.SilkS")
		)
		(fp_line
			(start -0.7874 -0.4064)
			(end 0.7874 -0.4064)
			(stroke
				(width 0.1524)
				(type default)
			)
			(layer "F.SilkS")
		)
		(fp_line
			(start 0.7874 -0.4064)
			(end 0.7874 0.4064)
			(stroke
				(width 0.1524)
				(type default)
			)
			(layer "F.SilkS")
		)
		(fp_line
			(start -0.67945 0.3048)
			(end -0.67945 -0.305054)
			(stroke
				(width 0.1)
				(type default)
			)
			(layer "F.Fab")
		)
		(fp_line
			(start -0.12065 0.3048)
			(end -0.67945 0.3048)
			(stroke
				(width 0.1)
				(type default)
			)
			(layer "F.Fab")
		)
		(fp_line
			(start 0.120396 0.3048)
			(end 0.120396 0.2794)
			(stroke
				(width 0.1)
				(type default)
			)
			(layer "F.Fab")
		)
		(fp_line
			(start 0.67945 0.3048)
			(end 0.120396 0.3048)
			(stroke
				(width 0.1)
				(type default)
			)
			(layer "F.Fab")
		)
		(fp_line
			(start -0.12065 0.2794)
			(end -0.12065 0.3048)
			(stroke
				(width 0.1)
				(type default)
			)
			(layer "F.Fab")
		)
		(fp_line
			(start 0.120396 0.2794)
			(end -0.12065 0.2794)
			(stroke
				(width 0.1)
				(type default)
			)
			(layer "F.Fab")
		)
		(fp_line
			(start -0.12065 -0.2794)
			(end 0.12065 -0.2794)
			(stroke
				(width 0.1)
				(type default)
			)
			(layer "F.Fab")
		)
		(fp_line
			(start 0.12065 -0.2794)
			(end 0.12065 -0.3048)
			(stroke
				(width 0.1)
				(type default)
			)
			(layer "F.Fab")
		)
		(fp_line
			(start 0.12065 -0.3048)
			(end 0.67945 -0.3048)
			(stroke
				(width 0.1)
				(type default)
			)
			(layer "F.Fab")
		)
		(fp_line
			(start 0.67945 -0.3048)
			(end 0.67945 0.3048)
			(stroke
				(width 0.1)
				(type default)
			)
			(layer "F.Fab")
		)
		(fp_line
			(start -0.67945 -0.305054)
			(end -0.12065 -0.305054)
			(stroke
				(width 0.1)
				(type default)
			)
			(layer "F.Fab")
		)
		(fp_line
			(start -0.12065 -0.305054)
			(end -0.12065 -0.2794)
			(stroke
				(width 0.1)
				(type default)
			)
			(layer "F.Fab")
		)
		(pad "1" smd circle
			(at -0.40005 0 270)
			(size 0 0)
			(layers "F.Cu" "F.Mask" "F.Paste")
			(net "HP_NIC6_EN")
		)
		(pad "2" smd circle
			(at 0.40005 0 270)
			(size 0 0)
			(layers "F.Cu" "F.Mask" "F.Paste")
			(net "P12V_NIC6_CO_EN")
		)
	)
	(footprint ""
		(layer "F.Cu")
		(at 367.54689 -37.47516)
		(property "Reference" "R6111"
			(at 0 0 0)
			(layer "F.SilkS")
			(hide yes)
			(effects
				(font
					(size 1.27 1.27)
				)
			)
		)
		(property "Value" ""
			(at 0 0 0)
			(layer "F.Fab")
			(effects
				(font
					(size 1.27 1.27)
				)
			)
		)
		(duplicate_pad_numbers_are_jumpers no)
		(fp_line
			(start -0.7874 -0.4064)
			(end 0.7874 -0.4064)
			(stroke
				(width 0.1524)
				(type default)
			)
			(layer "F.SilkS")
		)
		(fp_line
			(start -0.7874 0.4064)
			(end -0.7874 -0.4064)
			(stroke
				(width 0.1524)
				(type default)
			)
			(layer "F.SilkS")
		)
		(fp_line
			(start 0.7874 -0.4064)
			(end 0.7874 0.4064)
			(stroke
				(width 0.1524)
				(type default)
			)
			(layer "F.SilkS")
		)
		(fp_line
			(start 0.7874 0.4064)
			(end -0.7874 0.4064)
			(stroke
				(width 0.1524)
				(type default)
			)
			(layer "F.SilkS")
		)
		(fp_line
			(start -0.67945 -0.305054)
			(end -0.12065 -0.305054)
			(stroke
				(width 0.1)
				(type default)
			)
			(layer "F.Fab")
		)
		(fp_line
			(start -0.67945 0.3048)
			(end -0.67945 -0.305054)
			(stroke
				(width 0.1)
				(type default)
			)
			(layer "F.Fab")
		)
		(fp_line
			(start -0.12065 -0.305054)
			(end -0.12065 -0.2794)
			(stroke
				(width 0.1)
				(type default)
			)
			(layer "F.Fab")
		)
		(fp_line
			(start -0.12065 -0.2794)
			(end 0.12065 -0.2794)
			(stroke
				(width 0.1)
				(type default)
			)
			(layer "F.Fab")
		)
		(fp_line
			(start -0.12065 0.2794)
			(end -0.12065 0.3048)
			(stroke
				(width 0.1)
				(type default)
			)
			(layer "F.Fab")
		)
		(fp_line
			(start -0.12065 0.3048)
			(end -0.67945 0.3048)
			(stroke
				(width 0.1)
				(type default)
			)
			(layer "F.Fab")
		)
		(fp_line
			(start 0.120396 0.2794)
			(end -0.12065 0.2794)
			(stroke
				(width 0.1)
				(type default)
			)
			(layer "F.Fab")
		)
		(fp_line
			(start 0.120396 0.3048)
			(end 0.120396 0.2794)
			(stroke
				(width 0.1)
				(type default)
			)
			(layer "F.Fab")
		)
		(fp_line
			(start 0.12065 -0.3048)
			(end 0.67945 -0.3048)
			(stroke
				(width 0.1)
				(type default)
			)
			(layer "F.Fab")
		)
		(fp_line
			(start 0.12065 -0.2794)
			(end 0.12065 -0.3048)
			(stroke
				(width 0.1)
				(type default)
			)
			(layer "F.Fab")
		)
		(fp_line
			(start 0.67945 -0.3048)
			(end 0.67945 0.3048)
			(stroke
				(width 0.1)
				(type default)
			)
			(layer "F.Fab")
		)
		(fp_line
			(start 0.67945 0.3048)
			(end 0.120396 0.3048)
			(stroke
				(width 0.1)
				(type default)
			)
			(layer "F.Fab")
		)
		(pad "1" smd circle
			(at -0.40005 0)
			(size 0 0)
			(layers "F.Cu" "F.Mask" "F.Paste")
			(net "P3V3_SSD13")
		)
		(pad "2" smd circle
			(at 0.40005 0)
			(size 0 0)
			(layers "F.Cu" "F.Mask" "F.Paste")
			(net "P3V3_SSD13_PG_G1")
		)
	)
	(footprint ""
		(layer "F.Cu")
		(at 262.088122 -257.64871 -90)
		(property "Reference" "C3399"
			(at 0 0 270)
			(layer "F.SilkS")
			(hide yes)
			(effects
				(font
					(size 1.27 1.27)
				)
			)
		)
		(property "Value" ""
			(at 0 0 270)
			(layer "F.Fab")
			(effects
				(font
					(size 1.27 1.27)
				)
			)
		)
		(duplicate_pad_numbers_are_jumpers no)
		(fp_line
			(start -1.2954 0.5842)
			(end -1.2954 -0.5842)
			(stroke
				(width 0.1524)
				(type default)
			)
			(layer "F.SilkS")
		)
		(fp_line
			(start 1.2954 0.5842)
			(end -1.2954 0.5842)
			(stroke
				(width 0.1524)
				(type default)
			)
			(layer "F.SilkS")
		)
		(fp_line
			(start -1.2954 -0.5842)
			(end 1.2954 -0.5842)
			(stroke
				(width 0.1524)
				(type default)
			)
			(layer "F.SilkS")
		)
		(fp_line
			(start 1.2954 -0.5842)
			(end 1.2954 0.5842)
			(stroke
				(width 0.1524)
				(type default)
			)
			(layer "F.SilkS")
		)
		(fp_line
			(start -0.8636 0.4572)
			(end -0.8636 0.4064)
			(stroke
				(width 0.1)
				(type default)
			)
			(layer "F.Fab")
		)
		(fp_line
			(start 0.8636 0.4572)
			(end -0.8636 0.4572)
			(stroke
				(width 0.1)
				(type default)
			)
			(layer "F.Fab")
		)
		(fp_line
			(start -1.1938 0.4064)
			(end -1.1938 -0.4064)
			(stroke
				(width 0.1)
				(type default)
			)
			(layer "F.Fab")
		)
		(fp_line
			(start -0.8636 0.4064)
			(end -1.1938 0.4064)
			(stroke
				(width 0.1)
				(type default)
			)
			(layer "F.Fab")
		)
		(fp_line
			(start 0.8636 0.4064)
			(end 0.8636 0.4572)
			(stroke
				(width 0.1)
				(type default)
			)
			(layer "F.Fab")
		)
		(fp_line
			(start 1.1938 0.4064)
			(end 0.8636 0.4064)
			(stroke
				(width 0.1)
				(type default)
			)
			(layer "F.Fab")
		)
		(fp_line
			(start -1.1938 -0.4064)
			(end -0.8636 -0.4064)
			(stroke
				(width 0.1)
				(type default)
			)
			(layer "F.Fab")
		)
		(fp_line
			(start -0.8636 -0.4064)
			(end -0.8636 -0.4572)
			(stroke
				(width 0.1)
				(type default)
			)
			(layer "F.Fab")
		)
		(fp_line
			(start 0.8636 -0.4064)
			(end 1.1938 -0.4064)
			(stroke
				(width 0.1)
				(type default)
			)
			(layer "F.Fab")
		)
		(fp_line
			(start 1.1938 -0.4064)
			(end 1.1938 0.4064)
			(stroke
				(width 0.1)
				(type default)
			)
			(layer "F.Fab")
		)
		(fp_line
			(start -0.8636 -0.4572)
			(end 0.8636 -0.4572)
			(stroke
				(width 0.1)
				(type default)
			)
			(layer "F.Fab")
		)
		(fp_line
			(start 0.8636 -0.4572)
			(end 0.8636 -0.4064)
			(stroke
				(width 0.1)
				(type default)
			)
			(layer "F.Fab")
		)
		(pad "1" smd rect
			(at -0.7366 0 180)
			(size 0.7112 0.8128)
			(layers "F.Cu" "F.Mask" "F.Paste")
			(net "P1V8_PLL0_PEX2")
		)
		(pad "2" smd rect
			(at 0.7366 0 180)
			(size 0.7112 0.8128)
			(layers "F.Cu" "F.Mask" "F.Paste")
			(net "GND")
		)
	)
	(footprint ""
		(layer "F.Cu")
		(at 80.49514 -35.48253)
		(property "Reference" "U384"
			(at -2.46507 1.59893 90)
			(unlocked yes)
			(layer "F.SilkS")
			(effects
				(font
					(size 0.7874 0.5842)
					(thickness 0.1524)
				)
				(justify left)
			)
		)
		(property "Value" ""
			(at 0 0 0)
			(layer "F.Fab")
			(effects
				(font
					(size 1.27 1.27)
				)
			)
		)
		(duplicate_pad_numbers_are_jumpers no)
		(fp_line
			(start -1.3462 -1.1938)
			(end -1.3462 1.1684)
			(stroke
				(width 0.1524)
				(type default)
			)
			(layer "F.SilkS")
		)
		(fp_line
			(start -1.3462 1.1938)
			(end 1.3462 1.1938)
			(stroke
				(width 0.1524)
				(type default)
			)
			(layer "F.SilkS")
		)
		(fp_line
			(start 1.3462 -1.1938)
			(end -1.3462 -1.1938)
			(stroke
				(width 0.1524)
				(type default)
			)
			(layer "F.SilkS")
		)
		(fp_line
			(start 1.3462 1.1938)
			(end 1.3462 -1.1938)
			(stroke
				(width 0.1524)
				(type default)
			)
			(layer "F.SilkS")
		)
		(fp_poly
			(pts
				(xy -1.447038 -0.760476) (xy -2.052066 -0.457962) (xy -2.052066 -1.06299)
			)
			(stroke
				(width 0)
				(type default)
			)
			(fill yes)
			(layer "F.SilkS")
		)
		(fp_line
			(start -0.674878 -1.124966)
			(end -0.674878 1.124966)
			(stroke
				(width 0.1)
				(type default)
			)
			(layer "F.Fab")
		)
		(fp_line
			(start -0.674878 1.124966)
			(end 0.674878 1.124966)
			(stroke
				(width 0.1)
				(type default)
			)
			(layer "F.Fab")
		)
		(fp_line
			(start 0.674878 -1.124966)
			(end -0.674878 -1.124966)
			(stroke
				(width 0.1)
				(type default)
			)
			(layer "F.Fab")
		)
		(fp_line
			(start 0.674878 1.124966)
			(end 0.674878 -1.124966)
			(stroke
				(width 0.1)
				(type default)
			)
			(layer "F.Fab")
		)
		(fp_poly
			(pts
				(xy -1.447038 -0.760476) (xy -2.052066 -0.457962) (xy -2.052066 -1.06299)
			)
			(stroke
				(width 0)
				(type default)
			)
			(fill yes)
			(layer "F.Fab")
		)
		(pad "1" smd rect
			(at -0.899922 -0.750062)
			(size 0.6096 0.6096)
			(layers "F.Cu" "F.Mask" "F.Paste")
			(net "PWRGD_P3V3_SSD3_R")
		)
		(pad "2" smd rect
			(at -0.899922 0 90)
			(size 0.4064 0.6096)
			(layers "F.Cu" "F.Mask" "F.Paste")
			(net "RST_SMB_SSD3_N")
		)
		(pad "3" smd rect
			(at -0.899922 0.750062)
			(size 0.6096 0.6096)
			(layers "F.Cu" "F.Mask" "F.Paste")
			(net "GND")
		)
		(pad "4" smd rect
			(at 0.899922 0.750062)
			(size 0.6096 0.6096)
			(layers "F.Cu" "F.Mask" "F.Paste")
			(net "RST_SMB_SSD3_ISO_N")
		)
		(pad "5" smd rect
			(at 0.899922 -0.750062)
			(size 0.6096 0.6096)
			(layers "F.Cu" "F.Mask" "F.Paste")
			(net "P3V3_AUX")
		)
	)
	(footprint ""
		(layer "F.Cu")
		(at 386.866384 -250.070874 -90)
		(property "Reference" "R1404"
			(at 0 0 270)
			(layer "F.SilkS")
			(hide yes)
			(effects
				(font
					(size 1.27 1.27)
				)
			)
		)
		(property "Value" ""
			(at 0 0 270)
			(layer "F.Fab")
			(effects
				(font
					(size 1.27 1.27)
				)
			)
		)
		(duplicate_pad_numbers_are_jumpers no)
		(fp_line
			(start -0.7874 0.4064)
			(end -0.7874 -0.4064)
			(stroke
				(width 0.1524)
				(type default)
			)
			(layer "F.SilkS")
		)
		(fp_line
			(start 0.7874 0.4064)
			(end -0.7874 0.4064)
			(stroke
				(width 0.1524)
				(type default)
			)
			(layer "F.SilkS")
		)
		(fp_line
			(start -0.7874 -0.4064)
			(end 0.7874 -0.4064)
			(stroke
				(width 0.1524)
				(type default)
			)
			(layer "F.SilkS")
		)
		(fp_line
			(start 0.7874 -0.4064)
			(end 0.7874 0.4064)
			(stroke
				(width 0.1524)
				(type default)
			)
			(layer "F.SilkS")
		)
		(fp_line
			(start -0.67945 0.3048)
			(end -0.67945 -0.305054)
			(stroke
				(width 0.1)
				(type default)
			)
			(layer "F.Fab")
		)
		(fp_line
			(start -0.12065 0.3048)
			(end -0.67945 0.3048)
			(stroke
				(width 0.1)
				(type default)
			)
			(layer "F.Fab")
		)
		(fp_line
			(start 0.120396 0.3048)
			(end 0.120396 0.2794)
			(stroke
				(width 0.1)
				(type default)
			)
			(layer "F.Fab")
		)
		(fp_line
			(start 0.67945 0.3048)
			(end 0.120396 0.3048)
			(stroke
				(width 0.1)
				(type default)
			)
			(layer "F.Fab")
		)
		(fp_line
			(start -0.12065 0.2794)
			(end -0.12065 0.3048)
			(stroke
				(width 0.1)
				(type default)
			)
			(layer "F.Fab")
		)
		(fp_line
			(start 0.120396 0.2794)
			(end -0.12065 0.2794)
			(stroke
				(width 0.1)
				(type default)
			)
			(layer "F.Fab")
		)
		(fp_line
			(start -0.12065 -0.2794)
			(end 0.12065 -0.2794)
			(stroke
				(width 0.1)
				(type default)
			)
			(layer "F.Fab")
		)
		(fp_line
			(start 0.12065 -0.2794)
			(end 0.12065 -0.3048)
			(stroke
				(width 0.1)
				(type default)
			)
			(layer "F.Fab")
		)
		(fp_line
			(start 0.12065 -0.3048)
			(end 0.67945 -0.3048)
			(stroke
				(width 0.1)
				(type default)
			)
			(layer "F.Fab")
		)
		(fp_line
			(start 0.67945 -0.3048)
			(end 0.67945 0.3048)
			(stroke
				(width 0.1)
				(type default)
			)
			(layer "F.Fab")
		)
		(fp_line
			(start -0.67945 -0.305054)
			(end -0.12065 -0.305054)
			(stroke
				(width 0.1)
				(type default)
			)
			(layer "F.Fab")
		)
		(fp_line
			(start -0.12065 -0.305054)
			(end -0.12065 -0.2794)
			(stroke
				(width 0.1)
				(type default)
			)
			(layer "F.Fab")
		)
		(pad "1" smd circle
			(at -0.40005 0 270)
			(size 0 0)
			(layers "F.Cu" "F.Mask" "F.Paste")
			(net "PEX3_DBG_MODE4")
		)
		(pad "2" smd circle
			(at 0.40005 0 270)
			(size 0 0)
			(layers "F.Cu" "F.Mask" "F.Paste")
			(net "P1V8_PEX")
		)
	)
)
